(kicad_pcb
	(version 20241229)
	(generator "pcbnew")
	(generator_version "9.0")
	(general
		(thickness 1.63)
		(legacy_teardrops no)
	)
	(paper "A4")
	(title_block
		(title "CM4 Baseboard")
		(date "2026-01-05")
		(rev "1.1.1")
		(company "Antmicro Ltd")
		(comment 1 "www.antmicro.com")
		(comment 9 "footprints 62-66 of 506")
	)
	(layers
		(0 "F.Cu" signal)
		(4 "In1.Cu" power)
		(6 "In2.Cu" power)
		(8 "In3.Cu" signal)
		(10 "In4.Cu" signal)
		(2 "B.Cu" signal)
		(9 "F.Adhes" user "F.Adhesive")
		(11 "B.Adhes" user "B.Adhesive")
		(13 "F.Paste" user)
		(15 "B.Paste" user)
		(5 "F.SilkS" user "F.Silkscreen")
		(7 "B.SilkS" user "B.Silkscreen")
		(1 "F.Mask" user)
		(3 "B.Mask" user)
		(17 "Dwgs.User" user "User.Drawings")
		(19 "Cmts.User" user "User.Comments")
		(21 "Eco1.User" user "User.Eco1")
		(23 "Eco2.User" user "User.Eco2")
		(25 "Edge.Cuts" user)
		(27 "Margin" user)
		(31 "F.CrtYd" user "F.Courtyard")
		(29 "B.CrtYd" user "B.Courtyard")
		(35 "F.Fab" user)
		(33 "B.Fab" user)
	)
	(footprint "antmicro-footprints:R_0402_1005Metric"
		(layer "F.Cu")
		(at 132.817962 121.1915 -90)
		(descr "Resistor SMD 0402")
		(tags "resistor SMD 0402")
		(property "Reference" "R802"
			(at 6.895 -0.53 90)
			(layer "F.SilkS")
			(effects
				(font
					(size 0.7 0.7)
					(thickness 0.15)
				)
				(justify right bottom)
			)
		)
		(property "Value" "R_0R_0402"
			(at -1.011843 1.772047 90)
			(layer "F.Fab")
			(effects
				(font
					(size 0.7 0.7)
					(thickness 0.15)
				)
				(justify right bottom)
			)
		)
		(property "Datasheet" "https://industrial.panasonic.com/cdbs/www-data/pdf/RDA0000/AOA0000C301.pdf"
			(at 0 0 270)
			(layer "F.Fab")
			(hide yes)
			(effects
				(font
					(size 1.27 1.27)
					(thickness 0.15)
				)
			)
		)
		(property "MPN" "ERJ2GE0R00X"
			(at 0 0 270)
			(unlocked yes)
			(layer "F.Fab")
			(hide yes)
			(effects
				(font
					(size 1 1)
					(thickness 0.15)
				)
			)
		)
		(property "Manufacturer" "Panasonic"
			(at 0 0 270)
			(unlocked yes)
			(layer "F.Fab")
			(hide yes)
			(effects
				(font
					(size 1 1)
					(thickness 0.15)
				)
			)
		)
		(property "License" "Apache-2.0"
			(at 0 0 270)
			(unlocked yes)
			(layer "F.Fab")
			(hide yes)
			(effects
				(font
					(size 1 1)
					(thickness 0.15)
				)
			)
		)
		(property "Author" "Antmicro"
			(at 0 0 270)
			(unlocked yes)
			(layer "F.Fab")
			(hide yes)
			(effects
				(font
					(size 1 1)
					(thickness 0.15)
				)
			)
		)
		(property "Val" "0R"
			(at 0 0 270)
			(unlocked yes)
			(layer "F.Fab")
			(hide yes)
			(effects
				(font
					(size 1 1)
					(thickness 0.15)
				)
			)
		)
		(property "Tolerance" "~"
			(at 0 0 270)
			(unlocked yes)
			(layer "F.Fab")
			(hide yes)
			(effects
				(font
					(size 1 1)
					(thickness 0.15)
				)
			)
		)
		(property "Current" "1A"
			(at 0 0 270)
			(unlocked yes)
			(layer "F.Fab")
			(hide yes)
			(effects
				(font
					(size 1 1)
					(thickness 0.15)
				)
			)
		)
		(sheetname "/Peripherals/")
		(sheetfile "peripherals.kicad_sch")
		(attr smd)
		(fp_rect
			(start -0.925 -0.47)
			(end 0.925 0.47)
			(stroke
				(width 0.05)
				(type default)
			)
			(fill no)
			(layer "F.CrtYd")
		)
		(fp_rect
			(start -0.5 -0.25)
			(end 0.5 0.25)
			(stroke
				(width 0.15)
				(type solid)
			)
			(fill no)
			(layer "F.Fab")
		)
		(fp_text user "Author: Antmicro"
			(at -0.95 4.169 270)
			(layer "F.Fab")
			(effects
				(font
					(size 0.7 0.7)
					(thickness 0.15)
				)
				(justify left bottom)
			)
		)
		(fp_text user "${REFERENCE}"
			(at -0.95 3.168 270)
			(layer "F.Fab")
			(effects
				(font
					(size 0.7 0.7)
					(thickness 0.15)
				)
				(justify left bottom)
			)
		)
		(fp_text user "License: Apache-2.0"
			(at -0.95 5.169 270)
			(layer "F.Fab")
			(effects
				(font
					(size 0.7 0.7)
					(thickness 0.15)
				)
				(justify left bottom)
			)
		)
		(pad "1" smd roundrect
			(at -0.48 0 270)
			(size 0.59 0.64)
			(layers "F.Cu" "F.Mask" "F.Paste")
			(roundrect_rratio 0.25)
			(net 317 "/Peripherals/VLED")
			(pintype "passive")
		)
		(pad "2" smd roundrect
			(at 0.48 0 270)
			(size 0.59 0.64)
			(layers "F.Cu" "F.Mask" "F.Paste")
			(roundrect_rratio 0.25)
			(net 9 "+3V3")
			(pintype "passive")
		)
	)
	(footprint "antmicro-footprints:R_0402_1005Metric"
		(layer "F.Cu")
		(at 110.951464 158.0015 180)
		(descr "Resistor SMD 0402")
		(tags "resistor SMD 0402")
		(property "Reference" "R228"
			(at 1.873502 -2.425 180)
			(layer "F.SilkS")
			(effects
				(font
					(size 0.7 0.7)
					(thickness 0.15)
				)
				(justify left bottom)
			)
		)
		(property "Value" "R_0R_0402"
			(at -1.011843 1.772047 180)
			(layer "F.Fab")
			(effects
				(font
					(size 0.7 0.7)
					(thickness 0.15)
				)
				(justify left bottom)
			)
		)
		(property "Datasheet" "https://industrial.panasonic.com/cdbs/www-data/pdf/RDA0000/AOA0000C301.pdf"
			(at 0 0 180)
			(layer "F.Fab")
			(hide yes)
			(effects
				(font
					(size 1.27 1.27)
					(thickness 0.15)
				)
			)
		)
		(property "Manufacturer" "Panasonic"
			(at 0 0 180)
			(unlocked yes)
			(layer "F.Fab")
			(hide yes)
			(effects
				(font
					(size 1 1)
					(thickness 0.15)
				)
			)
		)
		(property "MPN" "ERJ2GE0R00X"
			(at 0 0 180)
			(unlocked yes)
			(layer "F.Fab")
			(hide yes)
			(effects
				(font
					(size 1 1)
					(thickness 0.15)
				)
			)
		)
		(property "Val" "0R"
			(at 0 0 180)
			(unlocked yes)
			(layer "F.Fab")
			(hide yes)
			(effects
				(font
					(size 1 1)
					(thickness 0.15)
				)
			)
		)
		(property "License" "Apache-2.0"
			(at 0 0 180)
			(unlocked yes)
			(layer "F.Fab")
			(hide yes)
			(effects
				(font
					(size 1 1)
					(thickness 0.15)
				)
			)
		)
		(property "Author" "Antmicro"
			(at 0 0 180)
			(unlocked yes)
			(layer "F.Fab")
			(hide yes)
			(effects
				(font
					(size 1 1)
					(thickness 0.15)
				)
			)
		)
		(property "Tolerance" "~"
			(at 0 0 180)
			(unlocked yes)
			(layer "F.Fab")
			(hide yes)
			(effects
				(font
					(size 1 1)
					(thickness 0.15)
				)
			)
		)
		(property "Current" "1A"
			(at 0 0 180)
			(unlocked yes)
			(layer "F.Fab")
			(hide yes)
			(effects
				(font
					(size 1 1)
					(thickness 0.15)
				)
			)
		)
		(sheetname "/Compute module/")
		(sheetfile "compute-module.kicad_sch")
		(attr smd)
		(fp_rect
			(start -0.925 -0.47)
			(end 0.925 0.47)
			(stroke
				(width 0.05)
				(type default)
			)
			(fill no)
			(layer "F.CrtYd")
		)
		(fp_rect
			(start -0.5 -0.25)
			(end 0.5 0.25)
			(stroke
				(width 0.15)
				(type solid)
			)
			(fill no)
			(layer "F.Fab")
		)
		(fp_text user "Author: Antmicro"
			(at -0.95 4.169 180)
			(layer "F.Fab")
			(effects
				(font
					(size 0.7 0.7)
					(thickness 0.15)
				)
				(justify left bottom)
			)
		)
		(fp_text user "${REFERENCE}"
			(at -0.95 3.168 180)
			(layer "F.Fab")
			(effects
				(font
					(size 0.7 0.7)
					(thickness 0.15)
				)
				(justify left bottom)
			)
		)
		(fp_text user "License: Apache-2.0"
			(at -0.95 5.169 180)
			(layer "F.Fab")
			(effects
				(font
					(size 0.7 0.7)
					(thickness 0.15)
				)
				(justify left bottom)
			)
		)
		(pad "1" smd roundrect
			(at -0.48 0 180)
			(size 0.59 0.64)
			(layers "F.Cu" "F.Mask" "F.Paste")
			(roundrect_rratio 0.25)
			(net 155 "/Compute module/T3_P")
			(pintype "passive")
		)
		(pad "2" smd roundrect
			(at 0.48 0 180)
			(size 0.59 0.64)
			(layers "F.Cu" "F.Mask" "F.Paste")
			(roundrect_rratio 0.25)
			(net 161 "/Compute module/NVMe.TX3_P")
			(pintype "passive")
		)
	)
	(footprint "antmicro-footprints:Conn_Molex_Nano-Fit_1x2_SMD_1054301202"
		(layer "F.Cu")
		(at 49.767962 116.1165 180)
		(descr "Molex Nano-Fit Power Connectors, 105430-xx02, 2 Pins per row")
		(tags "connector Molex Nano-Fit")
		(property "Reference" "J301"
			(at -4.5 -5.7 0)
			(layer "F.SilkS")
			(effects
				(font
					(size 0.7 0.7)
					(thickness 0.15)
				)
				(justify right bottom)
			)
		)
		(property "Value" "Molex_Nano-Fit_1x2_SMD_1054301202"
			(at 0 7.1 0)
			(layer "F.Fab")
			(effects
				(font
					(size 0.7 0.7)
					(thickness 0.15)
				)
				(justify right bottom)
			)
		)
		(property "Datasheet" "https://www.farnell.com/cad/3578051.pdf"
			(at 0 0 180)
			(layer "F.Fab")
			(hide yes)
			(effects
				(font
					(size 1.27 1.27)
					(thickness 0.15)
				)
			)
		)
		(property "Manufacturer" "Molex"
			(at 0 0 180)
			(unlocked yes)
			(layer "F.Fab")
			(hide yes)
			(effects
				(font
					(size 1 1)
					(thickness 0.15)
				)
			)
		)
		(property "MPN" "105430-1202"
			(at 0 0 180)
			(unlocked yes)
			(layer "F.Fab")
			(hide yes)
			(effects
				(font
					(size 1 1)
					(thickness 0.15)
				)
			)
		)
		(property "Author" "Antmicro"
			(at 0 0 180)
			(unlocked yes)
			(layer "F.Fab")
			(hide yes)
			(effects
				(font
					(size 1 1)
					(thickness 0.15)
				)
			)
		)
		(property "License" "Apache-2.0"
			(at 0 0 180)
			(unlocked yes)
			(layer "F.Fab")
			(hide yes)
			(effects
				(font
					(size 1 1)
					(thickness 0.15)
				)
			)
		)
		(sheetname "/Supply/")
		(sheetfile "supply.kicad_sch")
		(attr smd)
		(fp_line
			(start 4.48 2.298)
			(end 4.48 -4.5)
			(stroke
				(width 0.15)
				(type solid)
			)
			(layer "F.SilkS")
		)
		(fp_line
			(start 4.48 2.298)
			(end 4.28 2.698)
			(stroke
				(width 0.15)
				(type solid)
			)
			(layer "F.SilkS")
		)
		(fp_line
			(start 4.48 -4.5)
			(end 2.68 -4.5)
			(stroke
				(width 0.15)
				(type solid)
			)
			(layer "F.SilkS")
		)
		(fp_line
			(start 4.28 2.698)
			(end 4.28 4.299)
			(stroke
				(width 0.15)
				(type solid)
			)
			(layer "F.SilkS")
		)
		(fp_line
			(start -0.22 -4.5)
			(end 0.78 -4.5)
			(stroke
				(width 0.15)
				(type solid)
			)
			(layer "F.SilkS")
		)
		(fp_line
			(start -1.72 -4.5)
			(end -4.47 -4.5)
			(stroke
				(width 0.15)
				(type solid)
			)
			(layer "F.SilkS")
		)
		(fp_line
			(start -4.321 4.299)
			(end 4.28 4.299)
			(stroke
				(width 0.15)
				(type solid)
			)
			(layer "F.SilkS")
		)
		(fp_line
			(start -4.321 2.499)
			(end -4.321 4.299)
			(stroke
				(width 0.15)
				(type solid)
			)
			(layer "F.SilkS")
		)
		(fp_line
			(start -4.47 2.099)
			(end -4.321 2.499)
			(stroke
				(width 0.15)
				(type solid)
			)
			(layer "F.SilkS")
		)
		(fp_line
			(start -4.47 -4.5)
			(end -4.47 2.099)
			(stroke
				(width 0.15)
				(type solid)
			)
			(layer "F.SilkS")
		)
		(fp_circle
			(center 2.428 -4.91)
			(end 2.478 -4.91)
			(stroke
				(width 0.15)
				(type solid)
			)
			(fill yes)
			(layer "F.SilkS")
		)
		(fp_rect
			(start -4.77 -6.21)
			(end 4.77 6.11)
			(stroke
				(width 0.05)
				(type solid)
			)
			(fill no)
			(layer "F.CrtYd")
		)
		(fp_text user "${REFERENCE}"
			(at -4.77 8.11 180)
			(layer "F.Fab")
			(effects
				(font
					(size 0.7 0.7)
					(thickness 0.15)
				)
				(justify left bottom)
			)
		)
		(fp_text user "License: Apache-2.0"
			(at -4.77 10.51 180)
			(layer "F.Fab")
			(effects
				(font
					(size 0.7 0.7)
					(thickness 0.15)
				)
				(justify left bottom)
			)
		)
		(fp_text user "Author: Antmicro"
			(at -4.77 9.31 180)
			(layer "F.Fab")
			(effects
				(font
					(size 0.7 0.7)
					(thickness 0.15)
				)
				(justify left bottom)
			)
		)
		(pad "1" smd roundrect
			(at 1.528 -4.901 270)
			(size 2.5 1.24)
			(layers "F.Cu" "F.Mask" "F.Paste")
			(roundrect_rratio 0.25)
			(net 472 "Net-(D301-C)")
			(pintype "passive")
		)
		(pad "2" smd roundrect
			(at -0.97 -4.901 270)
			(size 2.5 1.24)
			(layers "F.Cu" "F.Mask" "F.Paste")
			(roundrect_rratio 0.25)
			(net 3 "GND")
			(pintype "passive")
		)
		(pad "MP" smd roundrect
			(at -3.54 0.029 180)
			(size 1.1 8.2)
			(layers "F.Cu" "F.Mask" "F.Paste")
			(roundrect_rratio 0.25)
			(net 3 "GND")
			(pintype "passive")
		)
		(pad "MP" smd roundrect
			(at 3.499 0.029 180)
			(size 1.1 8.2)
			(layers "F.Cu" "F.Mask" "F.Paste")
			(roundrect_rratio 0.25)
			(net 3 "GND")
			(pintype "passive")
		)
	)
	(footprint "antmicro-footprints:SOD-523"
		(layer "F.Cu")
		(at 88.692962 129.6665 180)
		(property "Reference" "D910"
			(at -0.695 3.68 0)
			(layer "F.SilkS")
			(effects
				(font
					(size 0.7 0.7)
					(thickness 0.15)
				)
				(justify right bottom)
			)
		)
		(property "Value" "RB521S30T1G"
			(at 0 1.499 0)
			(layer "F.Fab")
			(effects
				(font
					(size 0.7 0.7)
					(thickness 0.15)
				)
				(justify right bottom)
			)
		)
		(property "Datasheet" "https://www.onsemi.com/pdf/datasheet/rb521s30t1-d.pdf"
			(at 0 0 180)
			(layer "F.Fab")
			(hide yes)
			(effects
				(font
					(size 1.27 1.27)
					(thickness 0.15)
				)
			)
		)
		(property "MPN" "RB521S30T1G"
			(at 0 0 180)
			(unlocked yes)
			(layer "F.Fab")
			(hide yes)
			(effects
				(font
					(size 1 1)
					(thickness 0.15)
				)
			)
		)
		(property "Manufacturer" "ON Semiconductor"
			(at 0 0 180)
			(unlocked yes)
			(layer "F.Fab")
			(hide yes)
			(effects
				(font
					(size 1 1)
					(thickness 0.15)
				)
			)
		)
		(property "Author" "Antmicro"
			(at 0 0 180)
			(unlocked yes)
			(layer "F.Fab")
			(hide yes)
			(effects
				(font
					(size 1 1)
					(thickness 0.15)
				)
			)
		)
		(property "License" "Apache-2.0"
			(at 0 0 180)
			(unlocked yes)
			(layer "F.Fab")
			(hide yes)
			(effects
				(font
					(size 1 1)
					(thickness 0.15)
				)
			)
		)
		(sheetname "/USB/")
		(sheetfile "usb.kicad_sch")
		(attr smd)
		(fp_line
			(start -0.35 -0.5)
			(end -0.35 0.5)
			(stroke
				(width 0.15)
				(type solid)
			)
			(layer "F.SilkS")
		)
		(fp_rect
			(start -1 -0.6)
			(end 1 0.6)
			(stroke
				(width 0.05)
				(type solid)
			)
			(fill no)
			(layer "F.CrtYd")
		)
		(fp_line
			(start 0.65 -0.425)
			(end 0.65 0.423)
			(stroke
				(width 0.15)
				(type solid)
			)
			(layer "F.Fab")
		)
		(fp_line
			(start -0.35 -0.4)
			(end -0.35 0.4)
			(stroke
				(width 0.15)
				(type solid)
			)
			(layer "F.Fab")
		)
		(fp_line
			(start -0.652 0.423)
			(end 0.65 0.423)
			(stroke
				(width 0.15)
				(type solid)
			)
			(layer "F.Fab")
		)
		(fp_line
			(start -0.652 0.423)
			(end -0.652 -0.425)
			(stroke
				(width 0.15)
				(type solid)
			)
			(layer "F.Fab")
		)
		(fp_line
			(start -0.652 -0.425)
			(end 0.65 -0.425)
			(stroke
				(width 0.15)
				(type solid)
			)
			(layer "F.Fab")
		)
		(fp_text user "${REFERENCE}"
			(at -1.276 3.499 180)
			(layer "F.Fab")
			(effects
				(font
					(size 0.7 0.7)
					(thickness 0.15)
				)
				(justify left bottom)
			)
		)
		(fp_text user "Author: Antmicro"
			(at -1.276 4.7 180)
			(layer "F.Fab")
			(effects
				(font
					(size 0.7 0.7)
					(thickness 0.15)
				)
				(justify left bottom)
			)
		)
		(fp_text user "License: Apache-2.0"
			(at -1.276 5.9 180)
			(layer "F.Fab")
			(effects
				(font
					(size 0.7 0.7)
					(thickness 0.15)
				)
				(justify left bottom)
			)
		)
		(pad "1" smd roundrect
			(at -0.701 0 180)
			(size 0.5 0.6)
			(layers "F.Cu" "F.Mask" "F.Paste")
			(roundrect_rratio 0.25)
			(net 471 "Net-(D910-C)")
			(pinfunction "C")
			(pintype "passive")
		)
		(pad "2" smd roundrect
			(at 0.699 0 180)
			(size 0.5 0.6)
			(layers "F.Cu" "F.Mask" "F.Paste")
			(roundrect_rratio 0.25)
			(net 27 "/USB/USB_3V3")
			(pinfunction "A")
			(pintype "passive")
		)
	)
	(footprint "antmicro-footprints:R_0402_1005Metric"
		(layer "F.Cu")
		(at 76.467962 159.1665 90)
		(descr "Resistor SMD 0402")
		(tags "resistor SMD 0402")
		(property "Reference" "R244"
			(at -2.325 1.45 90)
			(layer "F.SilkS")
			(effects
				(font
					(size 0.7 0.7)
					(thickness 0.15)
				)
				(justify left bottom)
			)
		)
		(property "Value" "R_0R_0402"
			(at -1.011843 1.772047 90)
			(layer "F.Fab")
			(effects
				(font
					(size 0.7 0.7)
					(thickness 0.15)
				)
				(justify left bottom)
			)
		)
		(property "Datasheet" "https://industrial.panasonic.com/cdbs/www-data/pdf/RDA0000/AOA0000C301.pdf"
			(at 0 0 90)
			(layer "F.Fab")
			(hide yes)
			(effects
				(font
					(size 1.27 1.27)
					(thickness 0.15)
				)
			)
		)
		(property "Manufacturer" "Panasonic"
			(at 0 0 90)
			(unlocked yes)
			(layer "F.Fab")
			(hide yes)
			(effects
				(font
					(size 1 1)
					(thickness 0.15)
				)
			)
		)
		(property "MPN" "ERJ2GE0R00X"
			(at 0 0 90)
			(unlocked yes)
			(layer "F.Fab")
			(hide yes)
			(effects
				(font
					(size 1 1)
					(thickness 0.15)
				)
			)
		)
		(property "Val" "0R"
			(at 0 0 90)
			(unlocked yes)
			(layer "F.Fab")
			(hide yes)
			(effects
				(font
					(size 1 1)
					(thickness 0.15)
				)
			)
		)
		(property "License" "Apache-2.0"
			(at 0 0 90)
			(unlocked yes)
			(layer "F.Fab")
			(hide yes)
			(effects
				(font
					(size 1 1)
					(thickness 0.15)
				)
			)
		)
		(property "Author" "Antmicro"
			(at 0 0 90)
			(unlocked yes)
			(layer "F.Fab")
			(hide yes)
			(effects
				(font
					(size 1 1)
					(thickness 0.15)
				)
			)
		)
		(property "Tolerance" "~"
			(at 0 0 90)
			(unlocked yes)
			(layer "F.Fab")
			(hide yes)
			(effects
				(font
					(size 1 1)
					(thickness 0.15)
				)
			)
		)
		(property "Current" "1A"
			(at 0 0 90)
			(unlocked yes)
			(layer "F.Fab")
			(hide yes)
			(effects
				(font
					(size 1 1)
					(thickness 0.15)
				)
			)
		)
		(sheetname "/Compute module/")
		(sheetfile "compute-module.kicad_sch")
		(attr smd exclude_from_pos_files exclude_from_bom dnp)
		(fp_rect
			(start -0.925 -0.47)
			(end 0.925 0.47)
			(stroke
				(width 0.05)
				(type default)
			)
			(fill no)
			(layer "F.CrtYd")
		)
		(fp_rect
			(start -0.5 -0.25)
			(end 0.5 0.25)
			(stroke
				(width 0.15)
				(type solid)
			)
			(fill no)
			(layer "F.Fab")
		)
		(fp_text user "Author: Antmicro"
			(at -0.95 4.169 90)
			(layer "F.Fab")
			(effects
				(font
					(size 0.7 0.7)
					(thickness 0.15)
				)
				(justify left bottom)
			)
		)
		(fp_text user "${REFERENCE}"
			(at -0.95 3.168 90)
			(layer "F.Fab")
			(effects
				(font
					(size 0.7 0.7)
					(thickness 0.15)
				)
				(justify left bottom)
			)
		)
		(fp_text user "License: Apache-2.0"
			(at -0.95 5.169 90)
			(layer "F.Fab")
			(effects
				(font
					(size 0.7 0.7)
					(thickness 0.15)
				)
				(justify left bottom)
			)
		)
		(pad "1" smd roundrect
			(at -0.48 0 90)
			(size 0.59 0.64)
			(layers "F.Cu" "F.Mask" "F.Paste")
			(roundrect_rratio 0.25)
			(net 132 "/Compute module/CM4_3V3")
			(pintype "passive")
		)
		(pad "2" smd roundrect
			(at 0.48 0 90)
			(size 0.59 0.64)
			(layers "F.Cu" "F.Mask" "F.Paste")
			(roundrect_rratio 0.25)
			(net 129 "Net-(J201-Pad73)")
			(pintype "passive")
		)
	)
)
